(kicad_pcb
	(version 20260206)
	(generator "pcbnew")
	(generator_version "10.0")
	(general
		(thickness 1.6)
		(legacy_teardrops no)
	)
	(paper "A4")
	(title_block
		(title "timecard-production-celestica-r4006 — R4006-B0001-02_R01.brd")
		(comment 1 "Time Appliance Project (Time Card) / footprints 832-836 of 1113")
	)
	(layers
		(0 "F.Cu" signal "TOP")
		(4 "In1.Cu" signal "L02_GND1")
		(6 "In2.Cu" signal "L03_SIG1")
		(8 "In3.Cu" signal "L04_GND2")
		(10 "In4.Cu" signal "L05_VCC1")
		(12 "In5.Cu" signal "L06_VCC2")
		(14 "In6.Cu" signal "L07_GND3")
		(16 "In7.Cu" signal "L08_SIG2")
		(18 "In8.Cu" signal "L09_GND4")
		(2 "B.Cu" signal "BOTTOM")
		(9 "F.Adhes" user "F.Adhesive")
		(11 "B.Adhes" user "B.Adhesive")
		(13 "F.Paste" user "Package Geometry/Pastemask Top")
		(15 "B.Paste" user "Package Geometry/Pastemask Bottom")
		(5 "F.SilkS" user "Ref Des/Silkscreen Top")
		(7 "B.SilkS" user "Ref Des/Silkscreen Bottom")
		(1 "F.Mask" user "Board Geometry/Soldermask Top")
		(3 "B.Mask" user "Board Geometry/Soldermask Bottom")
		(17 "Dwgs.User" user "User.Drawings")
		(19 "Cmts.User" user "User.Comments")
		(21 "Eco1.User" user "User.Eco1")
		(23 "Eco2.User" user "User.Eco2")
		(25 "Edge.Cuts" user "Board Geometry/Outline")
		(27 "Margin" user)
		(31 "F.CrtYd" user "Package Geometry/Place Bound Top")
		(29 "B.CrtYd" user "Package Geometry/Place Bound Bottom")
		(35 "F.Fab" user "Ref Des/Assembly Top")
		(33 "B.Fab" user "Ref Des/Assembly Bottom")
	)
	(footprint ""
		(layer "B.Cu")
		(at 89.9922 -100.1268)
		(property "Reference" "C54"
			(at 3.683 0.03937 0)
			(unlocked yes)
			(layer "B.SilkS")
			(effects
				(font
					(size 0.7874 0.5842)
					(thickness 0.1524)
				)
				(justify mirror)
			)
		)
		(property "Value" "VAL*"
			(at -0.0762 2.067306 0)
			(unlocked yes)
			(layer "B.Fab")
			(hide yes)
			(effects
				(font
					(size 0.7874 0.5842)
					(thickness 0.1524)
				)
				(justify mirror)
			)
		)
		(property "Tolerance" "TOL*"
			(at -0.0762 3.032506 0)
			(unlocked yes)
			(layer "Cmts.User")
			(hide yes)
			(effects
				(font
					(size 0.7874 0.5842)
					(thickness 0.1524)
				)
				(justify mirror)
			)
		)
		(property "User Part Number" "PARTNUM*"
			(at -0.1016 4.023106 0)
			(unlocked yes)
			(layer "Cmts.User")
			(hide yes)
			(effects
				(font
					(size 0.7874 0.5842)
					(thickness 0.1524)
				)
				(justify mirror)
			)
		)
		(property "Device Type" "CAPACITOR-G105-0B222-FK,2200PFA"
			(at -0.0508 1.127506 0)
			(unlocked yes)
			(layer "B.Fab")
			(hide yes)
			(effects
				(font
					(size 0.7874 0.5842)
					(thickness 0.1524)
				)
				(justify mirror)
			)
		)
		(duplicate_pad_numbers_are_jumpers no)
		(fp_line
			(start -1.143 -0.5588)
			(end 1.143 -0.5588)
			(stroke
				(width 0.1)
				(type default)
			)
			(layer "B.SilkS")
		)
		(fp_line
			(start -1.143 0.5588)
			(end -1.143 -0.5588)
			(stroke
				(width 0.1)
				(type default)
			)
			(layer "B.SilkS")
		)
		(fp_line
			(start 1.143 -0.5588)
			(end 1.143 0.5588)
			(stroke
				(width 0.1)
				(type default)
			)
			(layer "B.SilkS")
		)
		(fp_line
			(start 1.143 0.5588)
			(end -1.143 0.5588)
			(stroke
				(width 0.1)
				(type default)
			)
			(layer "B.SilkS")
		)
		(fp_rect
			(start -1.143 0.5588)
			(end 1.143 -0.5588)
			(stroke
				(width 0)
				(type default)
			)
			(fill no)
			(layer "B.CrtYd")
		)
		(fp_line
			(start -0.508 -0.3048)
			(end 0.508 -0.3048)
			(stroke
				(width 0.1)
				(type default)
			)
			(layer "B.Fab")
		)
		(fp_line
			(start -0.508 0.3048)
			(end -0.508 -0.3048)
			(stroke
				(width 0.1)
				(type default)
			)
			(layer "B.Fab")
		)
		(fp_line
			(start 0.508 -0.3048)
			(end 0.508 0.3048)
			(stroke
				(width 0.1)
				(type default)
			)
			(layer "B.Fab")
		)
		(fp_line
			(start 0.508 0.3048)
			(end -0.508 0.3048)
			(stroke
				(width 0.1)
				(type default)
			)
			(layer "B.Fab")
		)
		(pad "1" smd rect
			(at 0.5334 0 180)
			(size 0.7112 0.6096)
			(layers "B.Cu" "B.Mask" "B.Paste")
			(net "UNNAMED_517_CAPACITOR_I17_1")
		)
		(pad "2" smd rect
			(at -0.5334 0 180)
			(size 0.7112 0.6096)
			(layers "B.Cu" "B.Mask" "B.Paste")
			(net "XP3R3V_AGND")
		)
		(zone
			(layer "B.Cu")
			(hatch none 0.5)
			(connect_pads
				(clearance 0)
			)
			(min_thickness 0.25)
			(keepout
				(tracks allowed)
				(vias not_allowed)
				(pads allowed)
				(copperpour not_allowed)
				(footprints allowed)
			)
			(placement
				(enabled no)
				(sheetname "")
			)
			(fill
				(thermal_gap 0.5)
				(thermal_bridge_width 0.5)
				(island_removal_mode 0)
			)
			(polygon
				(pts
					(xy 89.916 -99.822) (xy 90.0684 -99.822) (xy 90.0684 -100.4316) (xy 89.916 -100.4316)
				)
			)
		)
	)
	(footprint ""
		(layer "B.Cu")
		(at 95.758 -22.606 90)
		(property "Reference" "L10"
			(at 0 2.25425 270)
			(unlocked yes)
			(layer "B.SilkS")
			(effects
				(font
					(size 0.635 0.4064)
					(thickness 0.1524)
				)
				(justify mirror)
			)
		)
		(property "Value" "VAL*"
			(at -0.014732 2.526538 90)
			(unlocked yes)
			(layer "B.Fab")
			(hide yes)
			(effects
				(font
					(size 0.7874 0.5842)
					(thickness 0.000001)
				)
				(justify mirror)
			)
		)
		(property "Device Type" "FERRITEBEAD-G191-10097-01,600OA"
			(at -0.014732 1.600708 90)
			(unlocked yes)
			(layer "B.Fab")
			(hide yes)
			(effects
				(font
					(size 0.7874 0.5842)
					(thickness 0.000001)
				)
				(justify mirror)
			)
		)
		(property "User Part Number" "PARTNUM*"
			(at -0.02794 4.480814 90)
			(unlocked yes)
			(layer "Cmts.User")
			(hide yes)
			(effects
				(font
					(size 0.7874 0.5842)
					(thickness 0.000001)
				)
				(justify mirror)
			)
		)
		(property "Tolerance" "TOL*"
			(at -0.014732 3.503676 90)
			(unlocked yes)
			(layer "Cmts.User")
			(hide yes)
			(effects
				(font
					(size 0.7874 0.5842)
					(thickness 0.000001)
				)
				(justify mirror)
			)
		)
		(duplicate_pad_numbers_are_jumpers no)
		(fp_line
			(start 1.3208 -0.7112)
			(end -1.3208 -0.7112)
			(stroke
				(width 0.1)
				(type default)
			)
			(layer "B.SilkS")
		)
		(fp_line
			(start -1.3208 -0.7112)
			(end -1.3208 0.7112)
			(stroke
				(width 0.1)
				(type default)
			)
			(layer "B.SilkS")
		)
		(fp_line
			(start 1.3208 0.7112)
			(end 1.3208 -0.7112)
			(stroke
				(width 0.1)
				(type default)
			)
			(layer "B.SilkS")
		)
		(fp_line
			(start -1.3208 0.7112)
			(end 1.3208 0.7112)
			(stroke
				(width 0.1)
				(type default)
			)
			(layer "B.SilkS")
		)
		(fp_rect
			(start 1.3208 0.7112)
			(end -1.3208 -0.7112)
			(stroke
				(width 0)
				(type default)
			)
			(fill no)
			(layer "B.CrtYd")
		)
		(fp_line
			(start 0.8128 -0.4572)
			(end -0.8128 -0.4572)
			(stroke
				(width 0.1)
				(type default)
			)
			(layer "B.Fab")
		)
		(fp_line
			(start -0.8128 -0.4572)
			(end -0.8128 0.4572)
			(stroke
				(width 0.1)
				(type default)
			)
			(layer "B.Fab")
		)
		(fp_line
			(start 0.8128 0.4572)
			(end 0.8128 -0.4572)
			(stroke
				(width 0.1)
				(type default)
			)
			(layer "B.Fab")
		)
		(fp_line
			(start -0.8128 0.4572)
			(end 0.8128 0.4572)
			(stroke
				(width 0.1)
				(type default)
			)
			(layer "B.Fab")
		)
		(pad "1" smd rect
			(at 0.6858 0 270)
			(size 0.762 0.8636)
			(layers "B.Cu" "B.Mask" "B.Paste")
			(net "VDD3V3_OSC_125M")
		)
		(pad "2" smd rect
			(at -0.6858 0 270)
			(size 0.762 0.8636)
			(layers "B.Cu" "B.Mask" "B.Paste")
			(net "XP3R3V")
		)
		(zone
			(layer "B.Cu")
			(hatch none 0.5)
			(connect_pads
				(clearance 0)
			)
			(min_thickness 0.25)
			(keepout
				(tracks not_allowed)
				(vias allowed)
				(pads allowed)
				(copperpour not_allowed)
				(footprints allowed)
			)
			(placement
				(enabled no)
				(sheetname "")
			)
			(fill
				(thermal_gap 0.5)
				(thermal_bridge_width 0.5)
				(island_removal_mode 0)
			)
			(polygon
				(pts
					(xy 96.2152 -22.7584) (xy 95.3008 -22.7584) (xy 95.3008 -22.4536) (xy 96.2152 -22.4536)
				)
			)
		)
		(zone
			(layer "B.Cu")
			(hatch none 0.5)
			(connect_pads
				(clearance 0)
			)
			(min_thickness 0.25)
			(keepout
				(tracks allowed)
				(vias not_allowed)
				(pads allowed)
				(copperpour not_allowed)
				(footprints allowed)
			)
			(placement
				(enabled no)
				(sheetname "")
			)
			(fill
				(thermal_gap 0.5)
				(thermal_bridge_width 0.5)
				(island_removal_mode 0)
			)
			(polygon
				(pts
					(xy 96.2152 -22.7584) (xy 95.3008 -22.7584) (xy 95.3008 -22.4536) (xy 96.2152 -22.4536)
				)
			)
		)
	)
	(footprint ""
		(layer "B.Cu")
		(at 95.631 -82.169 180)
		(property "Reference" "R191"
			(at 0.254 5.67563 0)
			(unlocked yes)
			(layer "B.SilkS")
			(effects
				(font
					(size 0.7874 0.5842)
					(thickness 0.1524)
				)
				(justify mirror)
			)
		)
		(property "Value" "VAL*"
			(at -0.02032 2.13233 180)
			(unlocked yes)
			(layer "B.Fab")
			(hide yes)
			(effects
				(font
					(size 0.7874 0.5842)
					(thickness 0.1524)
				)
				(justify mirror)
			)
		)
		(property "Device Type" "RESISTOR-G155-14701-01,4.7KOHMA"
			(at -0.008382 1.210564 180)
			(unlocked yes)
			(layer "B.Fab")
			(hide yes)
			(effects
				(font
					(size 0.7874 0.5842)
					(thickness 0.1524)
				)
				(justify mirror)
			)
		)
		(property "User Part Number" "PARTNUM*"
			(at -0.02032 4.024884 180)
			(unlocked yes)
			(layer "Cmts.User")
			(hide yes)
			(effects
				(font
					(size 0.7874 0.5842)
					(thickness 0.1524)
				)
				(justify mirror)
			)
		)
		(property "Tolerance" "TOL*"
			(at -0.044704 3.05435 180)
			(unlocked yes)
			(layer "Cmts.User")
			(hide yes)
			(effects
				(font
					(size 0.7874 0.5842)
					(thickness 0.1524)
				)
				(justify mirror)
			)
		)
		(duplicate_pad_numbers_are_jumpers no)
		(fp_line
			(start 1.143 0.5588)
			(end -1.143 0.5588)
			(stroke
				(width 0.1)
				(type default)
			)
			(layer "B.SilkS")
		)
		(fp_line
			(start 1.143 -0.5588)
			(end 1.143 0.5588)
			(stroke
				(width 0.1)
				(type default)
			)
			(layer "B.SilkS")
		)
		(fp_line
			(start -1.143 0.5588)
			(end -1.143 -0.5588)
			(stroke
				(width 0.1)
				(type default)
			)
			(layer "B.SilkS")
		)
		(fp_line
			(start -1.143 -0.5588)
			(end 1.143 -0.5588)
			(stroke
				(width 0.1)
				(type default)
			)
			(layer "B.SilkS")
		)
		(fp_rect
			(start 1.143 -0.5588)
			(end -1.143 0.5588)
			(stroke
				(width 0)
				(type default)
			)
			(fill no)
			(layer "B.CrtYd")
		)
		(fp_line
			(start 0.508 0.3048)
			(end -0.508 0.3048)
			(stroke
				(width 0.1)
				(type default)
			)
			(layer "B.Fab")
		)
		(fp_line
			(start 0.508 -0.3048)
			(end 0.508 0.3048)
			(stroke
				(width 0.1)
				(type default)
			)
			(layer "B.Fab")
		)
		(fp_line
			(start -0.508 0.3048)
			(end -0.508 -0.3048)
			(stroke
				(width 0.1)
				(type default)
			)
			(layer "B.Fab")
		)
		(fp_line
			(start -0.508 -0.3048)
			(end 0.508 -0.3048)
			(stroke
				(width 0.1)
				(type default)
			)
			(layer "B.Fab")
		)
		(pad "1" smd rect
			(at 0.5334 0)
			(size 0.7112 0.6096)
			(layers "B.Cu" "B.Mask" "B.Paste")
			(net "XP3R3V_FPGA")
		)
		(pad "2" smd rect
			(at -0.5334 0)
			(size 0.7112 0.6096)
			(layers "B.Cu" "B.Mask" "B.Paste")
			(net "FLASH_CS_N")
		)
		(zone
			(layer "B.Cu")
			(hatch none 0.5)
			(connect_pads
				(clearance 0)
			)
			(min_thickness 0.25)
			(keepout
				(tracks allowed)
				(vias not_allowed)
				(pads allowed)
				(copperpour not_allowed)
				(footprints allowed)
			)
			(placement
				(enabled no)
				(sheetname "")
			)
			(fill
				(thermal_gap 0.5)
				(thermal_bridge_width 0.5)
				(island_removal_mode 0)
			)
			(polygon
				(pts
					(xy 95.5548 -81.8642) (xy 95.7072 -81.8642) (xy 95.7072 -82.4738) (xy 95.5548 -82.4738)
				)
			)
		)
	)
	(footprint ""
		(layer "B.Cu")
		(at 20.955 -38.1)
		(property "Reference" "R27"
			(at 0.127 4.48437 0)
			(unlocked yes)
			(layer "B.SilkS")
			(effects
				(font
					(size 0.7874 0.5842)
					(thickness 0.1524)
				)
				(justify mirror)
			)
		)
		(property "Value" "VAL*"
			(at -0.02032 2.13233 0)
			(unlocked yes)
			(layer "B.Fab")
			(hide yes)
			(effects
				(font
					(size 0.7874 0.5842)
					(thickness 0.1524)
				)
				(justify mirror)
			)
		)
		(property "Device Type" "RESISTOR-G155-133R0-01,33OHM,1%"
			(at -0.008382 1.210564 0)
			(unlocked yes)
			(layer "B.Fab")
			(hide yes)
			(effects
				(font
					(size 0.7874 0.5842)
					(thickness 0.1524)
				)
				(justify mirror)
			)
		)
		(property "User Part Number" "PARTNUM*"
			(at -0.02032 4.024884 0)
			(unlocked yes)
			(layer "Cmts.User")
			(hide yes)
			(effects
				(font
					(size 0.7874 0.5842)
					(thickness 0.1524)
				)
				(justify mirror)
			)
		)
		(property "Tolerance" "TOL*"
			(at -0.044704 3.05435 0)
			(unlocked yes)
			(layer "Cmts.User")
			(hide yes)
			(effects
				(font
					(size 0.7874 0.5842)
					(thickness 0.1524)
				)
				(justify mirror)
			)
		)
		(duplicate_pad_numbers_are_jumpers no)
		(fp_line
			(start -1.143 -0.5588)
			(end 1.143 -0.5588)
			(stroke
				(width 0.1)
				(type default)
			)
			(layer "B.SilkS")
		)
		(fp_line
			(start -1.143 0.5588)
			(end -1.143 -0.5588)
			(stroke
				(width 0.1)
				(type default)
			)
			(layer "B.SilkS")
		)
		(fp_line
			(start 1.143 -0.5588)
			(end 1.143 0.5588)
			(stroke
				(width 0.1)
				(type default)
			)
			(layer "B.SilkS")
		)
		(fp_line
			(start 1.143 0.5588)
			(end -1.143 0.5588)
			(stroke
				(width 0.1)
				(type default)
			)
			(layer "B.SilkS")
		)
		(fp_rect
			(start 1.143 0.5588)
			(end -1.143 -0.5588)
			(stroke
				(width 0)
				(type default)
			)
			(fill no)
			(layer "B.CrtYd")
		)
		(fp_line
			(start -0.508 -0.3048)
			(end 0.508 -0.3048)
			(stroke
				(width 0.1)
				(type default)
			)
			(layer "B.Fab")
		)
		(fp_line
			(start -0.508 0.3048)
			(end -0.508 -0.3048)
			(stroke
				(width 0.1)
				(type default)
			)
			(layer "B.Fab")
		)
		(fp_line
			(start 0.508 -0.3048)
			(end 0.508 0.3048)
			(stroke
				(width 0.1)
				(type default)
			)
			(layer "B.Fab")
		)
		(fp_line
			(start 0.508 0.3048)
			(end -0.508 0.3048)
			(stroke
				(width 0.1)
				(type default)
			)
			(layer "B.Fab")
		)
		(pad "1" smd rect
			(at 0.5334 0 180)
			(size 0.7112 0.6096)
			(layers "B.Cu" "B.Mask" "B.Paste")
			(net "PCIE_SMCLK")
		)
		(pad "2" smd rect
			(at -0.5334 0 180)
			(size 0.7112 0.6096)
			(layers "B.Cu" "B.Mask" "B.Paste")
			(net "R_PCA9546_I2C_SCL")
		)
		(zone
			(layer "B.Cu")
			(hatch none 0.5)
			(connect_pads
				(clearance 0)
			)
			(min_thickness 0.25)
			(keepout
				(tracks allowed)
				(vias not_allowed)
				(pads allowed)
				(copperpour not_allowed)
				(footprints allowed)
			)
			(placement
				(enabled no)
				(sheetname "")
			)
			(fill
				(thermal_gap 0.5)
				(thermal_bridge_width 0.5)
				(island_removal_mode 0)
			)
			(polygon
				(pts
					(xy 21.0312 -37.7952) (xy 21.0312 -38.4048) (xy 20.8788 -38.4048) (xy 20.8788 -37.7952)
				)
			)
		)
	)
	(footprint ""
		(layer "B.Cu")
		(at 134.0612 -66.8528 -90)
		(property "Reference" "R188"
			(at 0.0508 1.89357 270)
			(unlocked yes)
			(layer "B.SilkS")
			(effects
				(font
					(size 0.7874 0.5842)
					(thickness 0.1524)
				)
				(justify mirror)
			)
		)
		(property "Value" "VAL*"
			(at -0.02032 2.13233 270)
			(unlocked yes)
			(layer "B.Fab")
			(hide yes)
			(effects
				(font
					(size 0.7874 0.5842)
					(thickness 0.1524)
				)
				(justify mirror)
			)
		)
		(property "Tolerance" "TOL*"
			(at -0.044704 3.05435 270)
			(unlocked yes)
			(layer "Cmts.User")
			(hide yes)
			(effects
				(font
					(size 0.7874 0.5842)
					(thickness 0.1524)
				)
				(justify mirror)
			)
		)
		(property "User Part Number" "PARTNUM*"
			(at -0.02032 4.024884 270)
			(unlocked yes)
			(layer "Cmts.User")
			(hide yes)
			(effects
				(font
					(size 0.7874 0.5842)
					(thickness 0.1524)
				)
				(justify mirror)
			)
		)
		(property "Device Type" "RESISTOR-G155-03241-01,3.24KOHA"
			(at -0.008382 1.210564 270)
			(unlocked yes)
			(layer "B.Fab")
			(hide yes)
			(effects
				(font
					(size 0.7874 0.5842)
					(thickness 0.1524)
				)
				(justify mirror)
			)
		)
		(duplicate_pad_numbers_are_jumpers no)
		(fp_line
			(start -1.143 0.5588)
			(end -1.143 -0.5588)
			(stroke
				(width 0.1)
				(type default)
			)
			(layer "B.SilkS")
		)
		(fp_line
			(start 1.143 0.5588)
			(end -1.143 0.5588)
			(stroke
				(width 0.1)
				(type default)
			)
			(layer "B.SilkS")
		)
		(fp_line
			(start -1.143 -0.5588)
			(end 1.143 -0.5588)
			(stroke
				(width 0.1)
				(type default)
			)
			(layer "B.SilkS")
		)
		(fp_line
			(start 1.143 -0.5588)
			(end 1.143 0.5588)
			(stroke
				(width 0.1)
				(type default)
			)
			(layer "B.SilkS")
		)
		(fp_rect
			(start -1.143 -0.5588)
			(end 1.143 0.5588)
			(stroke
				(width 0)
				(type default)
			)
			(fill no)
			(layer "B.CrtYd")
		)
		(fp_line
			(start -0.508 0.3048)
			(end -0.508 -0.3048)
			(stroke
				(width 0.1)
				(type default)
			)
			(layer "B.Fab")
		)
		(fp_line
			(start 0.508 0.3048)
			(end -0.508 0.3048)
			(stroke
				(width 0.1)
				(type default)
			)
			(layer "B.Fab")
		)
		(fp_line
			(start -0.508 -0.3048)
			(end 0.508 -0.3048)
			(stroke
				(width 0.1)
				(type default)
			)
			(layer "B.Fab")
		)
		(fp_line
			(start 0.508 -0.3048)
			(end 0.508 0.3048)
			(stroke
				(width 0.1)
				(type default)
			)
			(layer "B.Fab")
		)
		(pad "1" smd rect
			(at 0.5334 0 90)
			(size 0.7112 0.6096)
			(layers "B.Cu" "B.Mask" "B.Paste")
			(net "SG")
		)
		(pad "2" smd rect
			(at -0.5334 0 90)
			(size 0.7112 0.6096)
			(layers "B.Cu" "B.Mask" "B.Paste")
			(net "XP1R8V_FB")
		)
		(zone
			(layer "B.Cu")
			(hatch none 0.5)
			(connect_pads
				(clearance 0)
			)
			(min_thickness 0.25)
			(keepout
				(tracks allowed)
				(vias not_allowed)
				(pads allowed)
				(copperpour not_allowed)
				(footprints allowed)
			)
			(placement
				(enabled no)
				(sheetname "")
			)
			(fill
				(thermal_gap 0.5)
				(thermal_bridge_width 0.5)
				(island_removal_mode 0)
			)
			(polygon
				(pts
					(xy 134.366 -66.929) (xy 133.7564 -66.929) (xy 133.7564 -66.7766) (xy 134.366 -66.7766)
				)
			)
		)
	)
)
